# T6G (Grand Teton) — schematic netlist excerpt (pin names and nets, part order shuffled) for the footprints in the layout excerpt that follows; sources: Cadence DE-HDL packaged netlist, KiCad conversion of 04192023_DAF0TMB3IC0_F0TG_MB_C_brd_V02_OCP.brd

R3294  Q_RES  0 5% CHIP  pkg 0402LF  page 144 : A = LED_M2_SSD_0_ACT_N ; B = LED_HDD_ACTIVITY_N
R69  Q_RES  10K 1% CHIP  pkg 0402LF  page 238 : A = CPU_FRU_ADDR0 ; B = GND
C946  Q_CAP_DIFFBUS  DIFF BUS_0.22UF 6.3V 20% X6S  pkg C0201  page 63 : \1\ = P5E_CPU0_P1_TX_C_DN<9> ; \2\ = P5E_CPU0_P1_TX_DN<9>

(kicad_pcb
	(version 20260206)
	(generator "pcbnew")
	(generator_version "10.0")
	(general
		(thickness 1.6)
		(legacy_teardrops no)
	)
	(paper "A4")
	(title_block
		(title "04192023_DAF0TMB3IC0_F0TG_MB_C_brd_V02_OCP.brd")
		(comment 1 "Grand Teton / footprints 1409-1411 of 8354")
	)
	(layers
		(0 "F.Cu" signal "TOP")
		(4 "In1.Cu" signal "GND")
		(6 "In2.Cu" signal "IN1")
		(8 "In3.Cu" signal "GND1")
		(10 "In4.Cu" signal "IN2")
		(12 "In5.Cu" signal "GND2")
		(14 "In6.Cu" signal "IN3")
		(16 "In7.Cu" signal "GND3")
		(18 "In8.Cu" signal "VCC")
		(20 "In9.Cu" signal "VCC1")
		(22 "In10.Cu" signal "GND4")
		(24 "In11.Cu" signal "IN4")
		(26 "In12.Cu" signal "GND5")
		(28 "In13.Cu" signal "IN5")
		(30 "In14.Cu" signal "GND6")
		(32 "In15.Cu" signal "IN6")
		(34 "In16.Cu" signal "GND7")
		(2 "B.Cu" signal "BOTTOM")
		(9 "F.Adhes" user "F.Adhesive")
		(11 "B.Adhes" user "B.Adhesive")
		(13 "F.Paste" user "Package Geometry/Pastemask Top")
		(15 "B.Paste" user "Package Geometry/Pastemask Bottom")
		(5 "F.SilkS" user "Ref Des/Silkscreen Top")
		(7 "B.SilkS" user "Ref Des/Silkscreen Bottom")
		(1 "F.Mask" user "Board Geometry/Soldermask Top")
		(3 "B.Mask" user "Board Geometry/Soldermask Bottom")
		(17 "Dwgs.User" user "User.Drawings")
		(19 "Cmts.User" user "User.Comments")
		(21 "Eco1.User" user "User.Eco1")
		(23 "Eco2.User" user "User.Eco2")
		(25 "Edge.Cuts" user "Board Geometry/Outline")
		(27 "Margin" user)
		(31 "F.CrtYd" user "Package Geometry/Place Bound Top")
		(29 "B.CrtYd" user "Package Geometry/Place Bound Bottom")
		(35 "F.Fab" user "Ref Des/Assembly Top")
		(33 "B.Fab" user "Ref Des/Assembly Bottom")
	)
	(footprint ""
		(layer "F.Cu")
		(at 150.31974 -101.672898)
		(property "Reference" "R3294"
			(at 0 0 0)
			(layer "F.SilkS")
			(hide yes)
			(effects
				(font
					(size 1.27 1.27)
				)
			)
		)
		(property "Value" ""
			(at 0 0 0)
			(layer "F.Fab")
			(effects
				(font
					(size 1.27 1.27)
				)
			)
		)
		(duplicate_pad_numbers_are_jumpers no)
		(fp_line
			(start -0.7874 -0.4064)
			(end 0.7874 -0.4064)
			(stroke
				(width 0.1524)
				(type default)
			)
			(layer "F.SilkS")
		)
		(fp_line
			(start -0.7874 0.4064)
			(end -0.7874 -0.4064)
			(stroke
				(width 0.1524)
				(type default)
			)
			(layer "F.SilkS")
		)
		(fp_line
			(start 0.7874 -0.4064)
			(end 0.7874 0.4064)
			(stroke
				(width 0.1524)
				(type default)
			)
			(layer "F.SilkS")
		)
		(fp_line
			(start 0.7874 0.4064)
			(end -0.7874 0.4064)
			(stroke
				(width 0.1524)
				(type default)
			)
			(layer "F.SilkS")
		)
		(fp_line
			(start -0.67945 -0.305054)
			(end -0.12065 -0.305054)
			(stroke
				(width 0.1)
				(type default)
			)
			(layer "F.Fab")
		)
		(fp_line
			(start -0.67945 0.3048)
			(end -0.67945 -0.305054)
			(stroke
				(width 0.1)
				(type default)
			)
			(layer "F.Fab")
		)
		(fp_line
			(start -0.12065 -0.305054)
			(end -0.12065 -0.2794)
			(stroke
				(width 0.1)
				(type default)
			)
			(layer "F.Fab")
		)
		(fp_line
			(start -0.12065 -0.2794)
			(end 0.12065 -0.2794)
			(stroke
				(width 0.1)
				(type default)
			)
			(layer "F.Fab")
		)
		(fp_line
			(start -0.12065 0.2794)
			(end -0.12065 0.3048)
			(stroke
				(width 0.1)
				(type default)
			)
			(layer "F.Fab")
		)
		(fp_line
			(start -0.12065 0.3048)
			(end -0.67945 0.3048)
			(stroke
				(width 0.1)
				(type default)
			)
			(layer "F.Fab")
		)
		(fp_line
			(start 0.120396 0.2794)
			(end -0.12065 0.2794)
			(stroke
				(width 0.1)
				(type default)
			)
			(layer "F.Fab")
		)
		(fp_line
			(start 0.120396 0.3048)
			(end 0.120396 0.2794)
			(stroke
				(width 0.1)
				(type default)
			)
			(layer "F.Fab")
		)
		(fp_line
			(start 0.12065 -0.3048)
			(end 0.67945 -0.3048)
			(stroke
				(width 0.1)
				(type default)
			)
			(layer "F.Fab")
		)
		(fp_line
			(start 0.12065 -0.2794)
			(end 0.12065 -0.3048)
			(stroke
				(width 0.1)
				(type default)
			)
			(layer "F.Fab")
		)
		(fp_line
			(start 0.67945 -0.3048)
			(end 0.67945 0.3048)
			(stroke
				(width 0.1)
				(type default)
			)
			(layer "F.Fab")
		)
		(fp_line
			(start 0.67945 0.3048)
			(end 0.120396 0.3048)
			(stroke
				(width 0.1)
				(type default)
			)
			(layer "F.Fab")
		)
		(pad "1" smd circle
			(at -0.40005 0)
			(size 0 0)
			(layers "F.Cu" "F.Mask" "F.Paste")
			(net "LED_M2_SSD_0_ACT_N")
		)
		(pad "2" smd circle
			(at 0.40005 0)
			(size 0 0)
			(layers "F.Cu" "F.Mask" "F.Paste")
			(net "LED_HDD_ACTIVITY_N")
		)
	)
	(footprint ""
		(layer "F.Cu")
		(at 302.241458 -113.843308 180)
		(property "Reference" "R69"
			(at 0 0 180)
			(layer "F.SilkS")
			(hide yes)
			(effects
				(font
					(size 1.27 1.27)
				)
			)
		)
		(property "Value" ""
			(at 0 0 180)
			(layer "F.Fab")
			(effects
				(font
					(size 1.27 1.27)
				)
			)
		)
		(duplicate_pad_numbers_are_jumpers no)
		(fp_line
			(start 0.7874 0.4064)
			(end -0.7874 0.4064)
			(stroke
				(width 0.1524)
				(type default)
			)
			(layer "F.SilkS")
		)
		(fp_line
			(start 0.7874 -0.4064)
			(end 0.7874 0.4064)
			(stroke
				(width 0.1524)
				(type default)
			)
			(layer "F.SilkS")
		)
		(fp_line
			(start -0.7874 0.4064)
			(end -0.7874 -0.4064)
			(stroke
				(width 0.1524)
				(type default)
			)
			(layer "F.SilkS")
		)
		(fp_line
			(start -0.7874 -0.4064)
			(end 0.7874 -0.4064)
			(stroke
				(width 0.1524)
				(type default)
			)
			(layer "F.SilkS")
		)
		(fp_line
			(start 0.67945 0.3048)
			(end 0.120396 0.3048)
			(stroke
				(width 0.1)
				(type default)
			)
			(layer "F.Fab")
		)
		(fp_line
			(start 0.67945 -0.3048)
			(end 0.67945 0.3048)
			(stroke
				(width 0.1)
				(type default)
			)
			(layer "F.Fab")
		)
		(fp_line
			(start 0.12065 -0.2794)
			(end 0.12065 -0.3048)
			(stroke
				(width 0.1)
				(type default)
			)
			(layer "F.Fab")
		)
		(fp_line
			(start 0.12065 -0.3048)
			(end 0.67945 -0.3048)
			(stroke
				(width 0.1)
				(type default)
			)
			(layer "F.Fab")
		)
		(fp_line
			(start 0.120396 0.3048)
			(end 0.120396 0.2794)
			(stroke
				(width 0.1)
				(type default)
			)
			(layer "F.Fab")
		)
		(fp_line
			(start 0.120396 0.2794)
			(end -0.12065 0.2794)
			(stroke
				(width 0.1)
				(type default)
			)
			(layer "F.Fab")
		)
		(fp_line
			(start -0.12065 0.3048)
			(end -0.67945 0.3048)
			(stroke
				(width 0.1)
				(type default)
			)
			(layer "F.Fab")
		)
		(fp_line
			(start -0.12065 0.2794)
			(end -0.12065 0.3048)
			(stroke
				(width 0.1)
				(type default)
			)
			(layer "F.Fab")
		)
		(fp_line
			(start -0.12065 -0.2794)
			(end 0.12065 -0.2794)
			(stroke
				(width 0.1)
				(type default)
			)
			(layer "F.Fab")
		)
		(fp_line
			(start -0.12065 -0.305054)
			(end -0.12065 -0.2794)
			(stroke
				(width 0.1)
				(type default)
			)
			(layer "F.Fab")
		)
		(fp_line
			(start -0.67945 0.3048)
			(end -0.67945 -0.305054)
			(stroke
				(width 0.1)
				(type default)
			)
			(layer "F.Fab")
		)
		(fp_line
			(start -0.67945 -0.305054)
			(end -0.12065 -0.305054)
			(stroke
				(width 0.1)
				(type default)
			)
			(layer "F.Fab")
		)
		(pad "1" smd circle
			(at -0.40005 0 180)
			(size 0 0)
			(layers "F.Cu" "F.Mask" "F.Paste")
			(net "CPU_FRU_ADDR0")
		)
		(pad "2" smd circle
			(at 0.40005 0 180)
			(size 0 0)
			(layers "F.Cu" "F.Mask" "F.Paste")
			(net "GND")
		)
	)
	(footprint ""
		(layer "F.Cu")
		(at 347.747844 -378.95403 -90)
		(property "Reference" "C946"
			(at 0 0 270)
			(layer "F.SilkS")
			(hide yes)
			(effects
				(font
					(size 1.27 1.27)
				)
			)
		)
		(property "Value" ""
			(at 0 0 270)
			(layer "F.Fab")
			(effects
				(font
					(size 1.27 1.27)
				)
			)
		)
		(duplicate_pad_numbers_are_jumpers no)
		(fp_line
			(start -0.299974 0.150114)
			(end -0.299974 -0.150114)
			(stroke
				(width 0.1)
				(type default)
			)
			(layer "F.Fab")
		)
		(fp_line
			(start 0.299974 0.150114)
			(end -0.299974 0.150114)
			(stroke
				(width 0.1)
				(type default)
			)
			(layer "F.Fab")
		)
		(fp_line
			(start -0.299974 -0.150114)
			(end 0.299974 -0.150114)
			(stroke
				(width 0.1)
				(type default)
			)
			(layer "F.Fab")
		)
		(fp_line
			(start 0.299974 -0.150114)
			(end 0.299974 0.150114)
			(stroke
				(width 0.1)
				(type default)
			)
			(layer "F.Fab")
		)
		(pad "1" smd rect
			(at -0.2667 0 270)
			(size 0.3048 0.381)
			(layers "F.Cu" "F.Mask" "F.Paste")
			(net "P5E_CPU0_P1_TX_C_DN<9>")
		)
		(pad "2" smd rect
			(at 0.2667 0 270)
			(size 0.3048 0.381)
			(layers "F.Cu" "F.Mask" "F.Paste")
			(net "P5E_CPU0_P1_TX_DN<9>")
		)
	)
)
